FILE_TYPE = CONNECTIVITY;
{Allegro Design Entry HDL 16.6-p007 (v16-6-112F) 10/10/2012}
"PAGE_NUMBER" = 209;
0"NC";
1"GND\g";
2"PVCCIN_CPU1\g";
3"VR_FET_SW_P12V_STBY_PVCCIN_CPU1\g";
4"GND\g";
5"GND\g";
6"GND\g";
7"GND\g";
8"GND\g";
9"GND\g";
10"PVCCIN_CPU1\g";
11"VR_FET_SW_P12V_STBY_PVCCIN_CPU1\g";
12"P12V_STBY\g";
13"P5V_STBY\g";
14"GND\g";
15"GND\g";
16"GND\g";
17"GND\g";
18"A_TSENSE_PVCCIN_CPU1";
19"VR_PVCCIN_CPU1_PHASE5"VOLTAGE"5";
20"UN$209$3D01R5F-GP$I66$2";
21"VR_PVCCIN_CPU1_PH5_PHASE"VOLTAGE"5";
22"VR_PVCCIN_CPU1_PH5_BOOT_R";
23"VR_PVCCIN_CPU1_PH5_BOOT";
24"VSENSE_PVCCIN_CPU1_P";
25"VR_FET_SW_P12V_PVCCIN_CPU1_R";
26"VR_PVCCIN_CPU1_PH5_OCSET";
27"VR_PVCCIN_CPU1_PWM5"VOLTAGE"3.6";
28"TP_PVCCIN_CPU1_PH5_GL_0";
29"VR_PVCCIN_CPU1_AIREF5";
30"NC_PVCCIN_CPU1_PH5_P31";
31"ISENSE_PVCCIN_CPU1_PH5_IMON";
32"VR_PVCCIN_CPU1_PH5_VCIN"VOLTAGE"5";
33"TP_PVCCIN_CPU1_PH5_GL_1";
34"VSENSE_PVCCIN_CPU1_SKT_VSEN";
35"VSENSE_PVCCIN_CPU1_SKT_VRTN";
36"VSENSE_PVCCIN_CPU1_N";
37"PVCCIN_PVSA_CPU1_IINSEN";
%"RES"
"1","(-5475,1450)","0","mstr_discrete","I10";
;
CDS_LOCATION"R1E7"
CDS_LIB"mstr_discrete"
ROOM"PVCCIN_CPU1_VSENSE_VR"
$SEC"1"
CDS_SEC"1"
BOM_COST"PROC_VRD_VCCIN_CPU0"
WATTAGE"1/16W"
PACK_TYPE"0402"
LOCATION"R1E7"
VALUE"0.0"
TOLERANCE"5%"
PART_NUMBER"G21497-005"
MATERIAL"CHIP";
"B"
$PN"2"35;
"A"
$PN"1"36;
%"RES"
"1","(-5500,1900)","0","mstr_discrete","I11";
;
CDS_LOCATION"R1E6"
ROOM"PVCCIN_CPU1_VSENSE_VR"
CDS_LIB"mstr_discrete"
$SEC"1"
CDS_SEC"1"
BOM_COST"PROC_VRD_VCCIN_CPU0"
WATTAGE"1/16W"
PACK_TYPE"0402"
MATERIAL"CHIP"
VALUE"0.0"
LOCATION"R1E6"
TOLERANCE"5%"
PART_NUMBER"G21497-005";
"B"
$PN"2"34;
"A"
$PN"1"24;
%"GND"
"1","(-4825,775)","0","mstr_symbols","I12";
;
ROOM"PVCCIN_CPU1_VSENSE_VR"
BOM_COST"PROC_VRD_VCCIN_CPU0"
HDL_POWER"GND"
BODY_TYPE"PLUMBING"
SIZE"1B"
CDS_LIB"mstr_symbols"
VOLTAGE"0";
"A\NAC"1;
%"RES"
"1","(-5500,2300)","0","mstr_discrete","I15";
;
MATERIAL"CHIP"
CDS_LIB"mstr_discrete"
BOM_COST"PROC_VRD_VCCIN_CPU0"
CDS_SEC"1"
CDS_LOCATION"R1E4"
$SEC"1"
ROOM"PVCCIN_CPU1_VSENSE_VR"
PACK_TYPE"0402"
WATTAGE"1/16W"
VALUE"100.0"
LOCATION"R1E4"
PART_NUMBER"G21796-017"
TOLERANCE"1%";
"B"
$PN"2"2;
"A"
$PN"1"24;
%"CAP"
"1","(-6350,4025)","0","mstr_discrete","I16";
;
CDS_SEC"1"
CDS_LOCATION"C1C26"
CDS_LIB"mstr_discrete"
ROOM"PVCCIN_CPU1_PWR_VR"
SEC"1"
SEC_TYPE"0402"
PACK_TYPE"0402"
MATERIAL"X6S"
VOLTAGE"16V"
TOLERANCE"10%"
PART_NUMBER"D97712-011"
VALUE"1.0UF"
LOCATION"C1C26";
"A"
$PN"1"3;
"B"
$PN"2"8;
%"CAP_A"
"1","(-6000,4050)","0","dev_discrete","I17";
;
CDS_LOCATION"C1C25"
CDS_LIB"dev_discrete"
SEC"1"
SEC_TYPE"0402V"
CDS_SEC"1"
ROOM"PVCCIN_CPU1_PWR_VR"
VALUE"0.1UF"
VOLTAGE"16V"
PART_NUMBER"A36096-030"
MATERIAL"X7R"
PACK_TYPE"0402V"
TOLERANCE"10%"
LOCATION"C1C25";
"B"
$PN"2"8;
"A"
$PN"1"3;
%"CAP"
"1","(-5625,4025)","0","mstr_discrete","I18";
;
CDS_SEC"1"
CDS_LOCATION"C1D32"
CDS_LIB"mstr_discrete"
ROOM"PVCCIN_CPU1_PWR_VR"
SEC"1"
SEC_TYPE"0402"
MATERIAL"X6S"
PART_NUMBER"D97712-011"
VOLTAGE"16V"
PACK_TYPE"0402"
TOLERANCE"10%"
VALUE"1.0UF"
LOCATION"C1D32";
"A"
$PN"1"32;
"B"
$PN"2"8;
%"PVCCIN_CPU1"
"1","(-4650,2450)","0","mstr_symbols","I19";
;
HDL_POWER"PVCCIN_CPU1"
BODY_TYPE"PLUMBING"
CDS_LIB"mstr_symbols"
VOLTAGE"2.0V";
"G\NAC"2;
%"CAP"
"1","(-5575,3450)","2","mstr_discrete","I20";
;
CDS_SEC"1"
CDS_LOCATION"C1C24"
CDS_LIB"mstr_discrete"
ROOM"PVCCIN_CPU1_PWR_VR"
NO_XNET_CONNECTION"1"
SEC"1"
SPOF"TRUE"
SEC_TYPE"0402"
VOLTAGE"16V"
TOLERANCE"10%"
MATERIAL"X7R"
PART_NUMBER"A36096-104"
PACK_TYPE"0402"
VALUE"0.220UF"
LOCATION"C1C24";
"A"
$PN"1"23;
"B"
$PN"2"21;
%"CAP_A"
"1","(-4975,4050)","2","dev_discrete","I21";
;
CDS_LIB"dev_discrete"
CDS_SEC"1"
SEC_TYPE"0402V"
CDS_LOCATION"C1C18"
SEC"1"
ROOM"PVCCIN_CPU1_PWR_VR"
PACK_TYPE"0402V"
VOLTAGE"6.3V"
PART_NUMBER"D97712-004"
MATERIAL"X6S"
LOCATION"C1C18"
TOLERANCE"10%"
VALUE"1.0UF";
"B"
$PN"2"8;
"A"
$PN"1"13;
%"CAP"
"1","(-4875,4050)","0","mstr_discrete","I22";
;
CDS_SEC"1"
CDS_LOCATION"C1D33"
CDS_LIB"mstr_discrete"
ROOM"PVCCIN_CPU1_PWR_VR"
SEC"1"
SEC_TYPE"0402"
MATERIAL"X7R"
VOLTAGE"16V"
TOLERANCE"10%"
VALUE"0.22UF"
LOCATION"C1D33"
PART_NUMBER"A36096-155"
PACK_TYPE"0402";
"A"
$PN"1"13;
"B"
$PN"2"8;
%"VCC_CORE"
"1","(-7175,4525)","0","mstr_symbols","I23";
;
CDS_LIB"mstr_symbols"
HDL_POWER"VR_FET_SW_P12V_STBY_PVCCIN_CPU1";
"A"3;
%"RES"
"1","(-5300,4650)","0","mstr_discrete","I24";
;
CDS_SEC"1"
CDS_LOCATION"R9P32"
CDS_LIB"mstr_discrete"
ROOM"PVCCIN_CPU1_PWR_VR"
SEC"1"
SEC_TYPE"0402"
VALUE"1.0"
PART_NUMBER"G21796-090"
WATTAGE"1/16W"
TOLERANCE"1%"
PACK_TYPE"0402"
LOCATION"R9P32"
MATERIAL"CHIP";
"B"
$PN"2"13;
"A"
$PN"1"32;
%"GND"
"1","(-3300,1000)","0","mstr_symbols","I26";
;
BODY_TYPE"PLUMBING"
SIZE"1B"
CDS_LIB"mstr_symbols"
VOLTAGE"0"
ROOM"PVCCIN_CPU1_FILTER_VR"
BOM_COST"PROC_VRD_VCCIN_CPU0"
HDL_POWER"GND";
"A\NAC"4;
%"GND"
"1","(-2250,850)","0","mstr_symbols","I29";
;
ROOM"PVCCIN_CPU1_FILTER_VR"
BOM_COST"PROC_VRD_VCCIN_CPU0"
VOLTAGE"0"
SIZE"1B"
CDS_LIB"mstr_symbols"
BODY_TYPE"PLUMBING"
HDL_POWER"GND";
"A\NAC"5;
%"RES"
"2","(-6300,1700)","0","mstr_discrete","I3";
;
CDS_LIB"mstr_discrete"
ROOM"PVCCIN_CPU1_VSENSE_VR"
CDS_LOCATION"R1E5"
$SEC"1"
CDS_SEC"1"
BOM_COST"PROC_VRD_VCCIN_CPU0"
TOLERANCE"1%"
WATTAGE"1/16W"
PACK_TYPE"0402"
VALUE"1.00K"
PART_NUMBER"G21796-026"
LOCATION"R1E5"
MATERIAL"EMPTY";
"A"
$PN"1"24;
"B"
$PN"2"36;
%"CAP_A"
"1","(-2250,1125)","0","dev_discrete","I30";
;
$SEC"1"
CDS_LIB"dev_discrete"
CDS_LOCATION"C1B16"
ROOM"PVCCIN_CPU1_FILTER_VR"
CDS_SEC"1"
PACK_TYPE"0402V"
VOLTAGE"16V"
TOLERANCE"10%"
VALUE"0.1UF"
LOCATION"C1B16"
PART_NUMBER"A36096-030"
MATERIAL"EMPTY";
"B"
$PN"2"5;
"A"
$PN"1"25;
%"INDUCTOR"
"1","(-3000,2250)","0","mstr_discrete","I32";
;
CDS_SEC"1"
ROOM"PVCCIN_CPU1_FILTER_VR"
CDS_LOCATION"L1B2"
SEC_TYPE"SM"
SEC"1"
CDS_LIB"mstr_discrete"
MATERIAL"IND"
LOCATION"L1B2"
VALUE"100NH"
PACK_TYPE"SM"
PART_NUMBER"D92183-019";
"INA\NAC"
$PN"1"12;
"INB\NAC"
$PN"2"25;
%"GND"
"1","(-2675,3125)","0","mstr_symbols","I34";
;
ROOM"PVCCIN_CPU1_PWR_VR"
BOM_COST"PROC_VRD_VCCIN_CPU0"
BODY_TYPE"PLUMBING"
VOLTAGE"0"
SIZE"1B"
CDS_LIB"mstr_symbols"
HDL_POWER"GND";
"A\NAC"6;
%"CAPP"
"1","(-1425,2075)","0","mstr_discrete","I35";
;
CDS_SEC"1"
CDS_LIB"mstr_discrete"
ROOM"PVCCIN_CPU1_FILTER_VR"
CDS_LOCATION"C1C1"
SEC"1"
SEC_TYPE"2626"
PART_NUMBER"A31228-047"
VOLTAGE"16V"
MATERIAL"OSCON"
PACK_TYPE"2626"
LOCATION"C1C1"
TOLERANCE"20%"
VALUE"270UF";
"B"
$PN"2"7;
"A"
$PN"1"11;
%"GND"
"1","(-1200,1650)","0","mstr_symbols","I36";
;
BOM_COST"PROC_VRD_VCCIN_CPU0"
ROOM"PVCCIN_CPU1_FILTER_VR"
BODY_TYPE"PLUMBING"
CDS_LIB"mstr_symbols"
VOLTAGE"0"
SIZE"1B"
HDL_POWER"GND";
"A\NAC"7;
%"CAPP"
"1","(-950,2050)","0","mstr_discrete","I37";
;
CDS_SEC"1"
CDS_LIB"mstr_discrete"
CDS_LOCATION"C1E18"
SEC_TYPE"2626"
SEC"1"
ROOM"PVCCIN_CPU1_FILTER_VR"
LOCATION"C1E18"
PACK_TYPE"2626"
MATERIAL"OSCON"
PART_NUMBER"A31228-047"
VALUE"270UF"
TOLERANCE"20%"
VOLTAGE"16V";
"B"
$PN"2"7;
"A"
$PN"1"11;
%"CAPP"
"1","(-600,2050)","0","mstr_discrete","I38";
;
CDS_SEC"1"
CDS_LOCATION"C1C2"
CDS_LIB"mstr_discrete"
ROOM"PVCCIN_CPU1_FILTER_VR"
SEC_TYPE"2626"
SEC"1"
PACK_TYPE"2626"
MATERIAL"OSCON"
VOLTAGE"16V"
TOLERANCE"20%"
PART_NUMBER"A31228-047"
VALUE"270UF"
LOCATION"C1C2";
"B"
$PN"2"7;
"A"
$PN"1"11;
%"RES"
"1","(-1850,2250)","0","mstr_discrete","I39";
;
CDS_SEC"1"
CDS_LIB"mstr_discrete"
CDS_LOCATION"R1B20"
SEC_TYPE"2010"
SEC"1"
ROOM"PVCCIN_CPU1_FILTER_VR"
PART_NUMBER"E30969-002"
LOCATION"R1B20"
WATTAGE"1W"
VALUE"0.001"
MATERIAL"CHIP"
TOLERANCE"1%"
PACK_TYPE"2010";
"B"
$PN"2"11;
"A"
$PN"1"25;
%"GND"
"1","(-7175,3500)","0","mstr_symbols","I4";
;
ROOM"PVCCIN_CPU1_PWR_VR"
BODY_TYPE"PLUMBING"
CDS_LIB"mstr_symbols"
VOLTAGE"0"
BOM_COST"PROC_VRD_VCCIN_CPU0"
HDL_POWER"GND"
SIZE"1B";
"A\NAC"8;
%"INDUCTOR"
"1","(-1450,3475)","0","mstr_discrete","I40";
;
CDS_LOCATION"L1C2"
ROOM"PVCCIN_CPU1_PWR_VR"
CDS_SEC"1"
$SEC"1"
CDS_LIB"mstr_discrete"
MATERIAL"IND"
PACK_TYPE"SM"
LOCATION"L1C2"
PART_NUMBER"D92183-034"
VALUE"0.12UH";
"INA\NAC"
$PN"1"19;
"INB\NAC"
$PN"2"10;
%"GND"
"1","(-375,2850)","0","mstr_symbols","I41";
;
ROOM"PVCCIN_CPU1_PWR_VR"
BOM_COST"PROC_VRD_VCCIN_CPU0"
BODY_TYPE"PLUMBING"
SIZE"1B"
CDS_LIB"mstr_symbols"
VOLTAGE"0"
HDL_POWER"GND";
"A\NAC"9;
%"CAP_A"
"1","(-750,3225)","0","dev_discrete","I42";
;
CDS_LIB"dev_discrete"
CDS_LOCATION"C1D24"
ROOM"PVCCIN_CPU1_PWR_VR"
SEC"1"
SEC_TYPE"0603V"
CDS_SEC"1"
BOM_COST"PROC_VRD_VCCIN_CPU0"
PACK_TYPE"0603V"
MATERIAL"X6S"
VOLTAGE"4V"
TOLERANCE"20%"
VALUE"22.0UF"
LOCATION"C1D24"
PART_NUMBER"E15431-004";
"B"
$PN"2"9;
"A"
$PN"1"10;
%"PVCCIN_CPU1"
"1","(-225,3650)","0","mstr_symbols","I43";
;
VOLTAGE"2.0V"
CDS_LIB"mstr_symbols"
BODY_TYPE"PLUMBING"
HDL_POWER"PVCCIN_CPU1";
"G\NAC"10;
%"VCC_CORE"
"1","(-600,2525)","0","mstr_symbols","I45";
;
CDS_LIB"mstr_symbols"
HDL_POWER"VR_FET_SW_P12V_STBY_PVCCIN_CPU1";
"A"11;
%"CAP"
"1","(-7175,4025)","0","mstr_discrete","I5";
;
CDS_SEC"1"
CDS_LOCATION"C9N27"
CDS_LIB"mstr_discrete"
ROOM"PVCCIN_CPU1_PWR_VR"
SEC"1"
SEC_TYPE"0805"
LOCATION"C9N27"
VALUE"10UF"
PART_NUMBER"C95333-007"
PACK_TYPE"0805"
MATERIAL"X6S"
VOLTAGE"16V"
TOLERANCE"10%";
"A"
$PN"1"3;
"B"
$PN"2"8;
%"ADM4073"
"1","(-2775,1350)","2","mstr_analog","I52";
;
CDS_SEC"1"
CDS_LIB"mstr_analog"
ROOM"PVCCIN_CPU1_FILTER_VR"
CDS_LOCATION"U1B3"
SEC"1"
SEC_TYPE"SM"
PACK_TYPE"SM"
MATERIAL"EMPTY"
PART_NUMBER"G12194-001"
LOCATION"U1B3";
"GND<0>"
$PN"1"4;
"GND<1>"
$PN"2"4;
"OUT"
$PN"6"37;
"RSN"
$PN"5"11;
"RSP"
$PN"4"25;
"VCC"
$PN"3"25;
%"P12V_STBY"
"1","(-3350,2475)","0","mstr_symbols","I53";
;
HDL_POWER"P12V_STBY"
VOLTAGE"12.0V"
CDS_LIB"mstr_symbols"
BODY_TYPE"PLUMBING"
SIZE"1B";
"G\NAC"12;
%"P5V_STBY"
"1","(-4550,4750)","0","mstr_symbols","I54";
;
HDL_POWER"P5V_STBY"
VOLTAGE"5.0V"
BODY_TYPE"PLUMBING"
SIZE"1B"
CDS_LIB"mstr_symbols";
"G\NAC"13;
%"CAP_A"
"1","(-375,3250)","0","dev_discrete","I55";
;
CDS_LIB"dev_discrete"
CDS_LOCATION"C9P20"
SEC"1"
SEC_TYPE"0603V"
CDS_SEC"1"
VALUE"22.0UF"
LOCATION"C9P20"
PACK_TYPE"0603V"
VOLTAGE"4V"
MATERIAL"X6S"
TOLERANCE"20%"
PART_NUMBER"E15431-004";
"B"
$PN"2"9;
"A"
$PN"1"10;
%"IR354XX"
"1","(-3250,3775)","0","mstr_discrete","I56";
;
CDS_SEC"1"
CDS_LIB"mstr_discrete"
CDS_LOCATION"EU1C3"
ROOM"PVCCIN_CPU1_PWR_VR"
PACK_TYPE"SM"
SEC"1"
SEC_TYPE"SM"
PART_NUMBER"H73688-001"
MATERIAL"IC"
LOCATION"EU1C3"
VALUE"IR35411";
"TOUT_FLT"
$PN"36"18;
"NC"
$PN"31"30;
"OCSET"
$PN"37"26;
"IOUT"
$PN"38"31;
"SW"
$PN"10"19;
"BOOST"
$PN"33"22;
"REFIN"
$PN"39"29;
"PWM"
$PN"34"27;
"PHASE"
$PN"32"21;
"VIN<0>"
$PN"25"3;
"VCC"
$PN"3"32;
"VIN<1>"
$PN"30"3;
"EN"
$PN"35"13;
"VDRV"
$PN"4"13;
"VOS"
$PN"1"10;
"LGND"
$PN"2"6;
"PGND<1>"
$PN"7"6;
"PGND<2>"
$PN"40"6;
"PGND<0>"
$PN"5"6;
"GL<0>"
$PN"6"28;
"GL<1>"
$PN"41"33;
%"RES"
"2","(-1000,3925)","0","mstr_discrete","I59";
;
CDS_LOCATION"R1D52"
CDS_LIB"mstr_discrete"
CDS_SEC"1"
$SEC"1"
PACK_TYPE"0402"
TOLERANCE"1%"
WATTAGE"1/16W"
VALUE"68.1K"
MATERIAL"EMPTY"
LOCATION"R1D52"
PART_NUMBER"G21796-187";
"A"
$PN"1"26;
"B"
$PN"2"14;
%"GND"
"1","(-1000,3675)","0","mstr_symbols","I60";
;
ROOM"PVCCIN_CPU1_FILTER_VR"
BOM_COST"PROC_VRD_VCCIN_CPU0"
BODY_TYPE"PLUMBING"
SIZE"1B"
CDS_LIB"mstr_symbols"
VOLTAGE"0"
HDL_POWER"GND";
"A\NAC"14;
%"CAP_A"
"1","(-3950,3275)","0","dev_discrete","I62";
;
CDS_SEC"1"
$SEC"1"
CDS_LOCATION"CT13"
ROOM"PVCCIN_CPU0_PWR_VR"
CDS_LIB"dev_discrete"
PART_NUMBER"A36096-030"
PACK_TYPE"0402V"
VOLTAGE"16V"
VALUE"0.1UF"
LOCATION"CT13"
MATERIAL"X7R"
TOLERANCE"10%"
STATUS"NOPOP";
"B"
$PN"2"15;
"A"
$PN"1"29;
%"GND"
"1","(-3950,3025)","0","mstr_symbols","I63";
;
BODY_TYPE"PLUMBING"
ROOM"PVCCIN_CPU0_PWR_VR"
BOM_COST"PROC_VRD_VCCIN_CPU0"
SIZE"1B"
VOLTAGE"0"
HDL_POWER"GND"
CDS_LIB"mstr_symbols";
"A\NAC"15;
%"SC2K2P50V3KX-GP"
"1","(-2400,3300)","0","w_hdl","I64";
;
CDS_SEC"1"
$SEC"1"
CDS_LOCATION"CT14"
PART_NUMBER"78.22224.2BL"
PACK_TYPE"SMD-BCG6"
CDS_LMAN_SYM_OUTLINE"-50,25,50,-25"
CDS_LIB"w_hdl"
VALUE"SC2K2P50V3KX-GP"
STATUS"NOPOP"
LOCATION"CT14";
"2"
$PN"2"20;
"1"
$PN"1"19;
%"GND"
"1","(-2400,2800)","0","mstr_symbols","I65";
;
CDS_LIB"mstr_symbols"
HDL_POWER"GND"
SIZE"1B"
VOLTAGE"0"
BODY_TYPE"PLUMBING"
BOM_COST"PROC_VRD_VCCIN_CPU0"
ROOM"PVCCIN_CPU0_PWR_VR";
"A\NAC"16;
%"3D01R5F-GP"
"1","(-2400,3025)","4","w_hdl","I66";
;
CDS_SEC"1"
$SEC"1"
CDS_LOCATION"RT10"
CDS_LMAN_SYM_OUTLINE"-50,75,50,-75"
CDS_LIB"w_hdl"
PART_NUMBER"64.3R015.16L"
PACK_TYPE"SMD-RG5"
VALUE"3D01R5F-GP"
STATUS"NOPOP"
LOCATION"RT10";
"2"
$PN"2"20;
"1"
$PN"1"16;
%"CAP"
"1","(-1950,3825)","0","mstr_discrete","I67";
;
CDS_SEC"1"
$SEC"1"
CDS_LOCATION"CT15"
ROOM"VDDQ_KLM_PWR_VR"
CDS_LIB"mstr_discrete"
TOLERANCE"10%"
PACK_TYPE"0402LF"
LOCATION"CT15"
STATUS"NOPOP"
MATERIAL"X7R"
PART_NUMBER"A36096-046"
VOLTAGE"50V"
VALUE"1000PF";
"A"
$PN"1"18;
"B"
$PN"2"17;
%"GND"
"1","(-1950,3575)","0","mstr_symbols","I68";
;
ROOM"VDDQ_KLM_PWR_VR"
VOLTAGE"0"
BODY_TYPE"PLUMBING"
SIZE"1B"
HDL_POWER"GND"
CDS_LIB"mstr_symbols";
"A\NAC"17;
%"RES"
"1","(-4800,3575)","0","mstr_discrete","I69";
;
CDS_SEC"1"
$SEC"1"
CDS_LOCATION"RT9"
BOM_COST"DEBUG"
ROOM"BMC_DEBUG_HEADER"
CDS_LIB"mstr_discrete"
LOCATION"RT9"
PART_NUMBER"G21497-005"
PACK_TYPE"0402"
MATERIAL"CHIP"
TOLERANCE"5%"
VALUE"0.0"
WATTAGE"1/16W";
"B"
$PN"2"22;
"A"
$PN"1"23;
%"CAP"
"1","(-6900,4025)","0","mstr_discrete","I7";
;
CDS_SEC"1"
CDS_LOCATION"C9N26"
CDS_LIB"mstr_discrete"
ROOM"PVCCIN_CPU1_PWR_VR"
SEC"1"
SEC_TYPE"0805"
MATERIAL"X6S"
VOLTAGE"16V"
PACK_TYPE"0805"
TOLERANCE"10%"
PART_NUMBER"C95333-007"
VALUE"10UF"
LOCATION"C9N26";
"A"
$PN"1"3;
"B"
$PN"2"8;
%"CAP"
"1","(-6625,3975)","0","mstr_discrete","I8";
;
CDS_SEC"1"
CDS_LOCATION"C9N25"
CDS_LIB"mstr_discrete"
ROOM"PVCCIN_CPU1_PWR_VR"
SEC"1"
SEC_TYPE"0805"
PACK_TYPE"0805"
VALUE"10UF"
TOLERANCE"10%"
VOLTAGE"16V"
MATERIAL"X6S"
PART_NUMBER"C95333-007"
LOCATION"C9N25";
"A"
$PN"1"3;
"B"
$PN"2"8;
%"RES"
"1","(-5475,1050)","0","mstr_discrete","I9";
;
MATERIAL"CHIP"
ROOM"PVCCIN_CPU1_VSENSE_VR"
BOM_COST"PROC_VRD_VCCIN_CPU0"
CDS_LOCATION"R1E8"
CDS_LIB"mstr_discrete"
$SEC"1"
CDS_SEC"1"
WATTAGE"1/16W"
PACK_TYPE"0402"
TOLERANCE"1%"
VALUE"100.0"
LOCATION"R1E8"
PART_NUMBER"G21796-017";
"B"
$PN"2"1;
"A"
$PN"1"36;
END.
